# BASEBOARD_FAB2 (Tioga Pass) — schematic netlist excerpt (pin names and nets, part order shuffled) for the footprints in the layout excerpt that follows; sources: Cadence DE-HDL packaged netlist, KiCad conversion of Wiwynn_Tioga_Pass_MB.brd

C1G22  CAP_A  0.1UF 16V 10% X7R  pkg 0402V  page 223 : A = VR_PVDDQ_GHJ_VD12 ; B = GND

(kicad_pcb
	(version 20260206)
	(generator "pcbnew")
	(generator_version "10.0")
	(general
		(thickness 1.6)
		(legacy_teardrops no)
	)
	(paper "A4")
	(title_block
		(title "Wiwynn_Tioga_Pass_MB.brd")
		(comment 1 "Tioga Pass / footprints 1250-1250 of 4770")
	)
	(layers
		(0 "F.Cu" signal "TOP")
		(4 "In1.Cu" signal "L2GND")
		(6 "In2.Cu" signal "L3")
		(8 "In3.Cu" signal "L4GND")
		(10 "In4.Cu" signal "L5")
		(12 "In5.Cu" signal "L6GND")
		(14 "In6.Cu" signal "L7VCC")
		(16 "In7.Cu" signal "L8VCC")
		(18 "In8.Cu" signal "L9GND")
		(20 "In9.Cu" signal "L10")
		(22 "In10.Cu" signal "L11GND")
		(24 "In11.Cu" signal "L12")
		(26 "In12.Cu" signal "L13GND")
		(2 "B.Cu" signal "BOTTOM")
		(9 "F.Adhes" user "F.Adhesive")
		(11 "B.Adhes" user "B.Adhesive")
		(13 "F.Paste" user "Package Geometry/Pastemask Top")
		(15 "B.Paste" user "Package Geometry/Pastemask Bottom")
		(5 "F.SilkS" user "Ref Des/Silkscreen Top")
		(7 "B.SilkS" user "Ref Des/Silkscreen Bottom")
		(1 "F.Mask" user "Board Geometry/Soldermask Top")
		(3 "B.Mask" user "Board Geometry/Soldermask Bottom")
		(17 "Dwgs.User" user "User.Drawings")
		(19 "Cmts.User" user "User.Comments")
		(21 "Eco1.User" user "User.Eco1")
		(23 "Eco2.User" user "User.Eco2")
		(25 "Edge.Cuts" user "Board Geometry/Outline")
		(27 "Margin" user)
		(31 "F.CrtYd" user "Package Geometry/Place Bound Top")
		(29 "B.CrtYd" user "Package Geometry/Place Bound Bottom")
		(35 "F.Fab" user "Ref Des/Assembly Top")
		(33 "B.Fab" user "Ref Des/Assembly Bottom")
	)
	(footprint ""
		(layer "F.Cu")
		(at 13.941806 2.692654 90)
		(property "Reference" "C1G22"
			(at 0 0 90)
			(layer "F.SilkS")
			(hide yes)
			(effects
				(font
					(size 1.27 1.27)
				)
			)
		)
		(property "Value" ""
			(at 0 0 90)
			(layer "F.Fab")
			(effects
				(font
					(size 1.27 1.27)
				)
			)
		)
		(duplicate_pad_numbers_are_jumpers no)
		(fp_rect
			(start 0.3048 -0.1016)
			(end -0.3048 0.9906)
			(stroke
				(width 0)
				(type default)
			)
			(fill no)
			(layer "F.CrtYd")
		)
		(fp_line
			(start 0.3048 -0.1016)
			(end -0.3048 -0.1016)
			(stroke
				(width 0.1)
				(type default)
			)
			(layer "F.Fab")
		)
		(fp_line
			(start -0.3048 -0.1016)
			(end -0.3048 0.9906)
			(stroke
				(width 0.1)
				(type default)
			)
			(layer "F.Fab")
		)
		(fp_line
			(start 0.3048 0.9906)
			(end 0.3048 -0.1016)
			(stroke
				(width 0.1)
				(type default)
			)
			(layer "F.Fab")
		)
		(fp_line
			(start -0.3048 0.9906)
			(end 0.3048 0.9906)
			(stroke
				(width 0.1)
				(type default)
			)
			(layer "F.Fab")
		)
		(pad "1" smd rect
			(at 0 0 90)
			(size 0.508 0.508)
			(layers "F.Cu" "F.Mask" "F.Paste")
			(net "VR_PVDDQ_GHJ_VD12")
		)
		(pad "2" smd rect
			(at 0 0.889 90)
			(size 0.508 0.508)
			(layers "F.Cu" "F.Mask" "F.Paste")
			(net "GND")
		)
		(zone
			(layer "F.Cu")
			(hatch none 0.5)
			(connect_pads
				(clearance 0)
			)
			(min_thickness 0.25)
			(keepout
				(tracks not_allowed)
				(vias allowed)
				(pads allowed)
				(copperpour not_allowed)
				(footprints allowed)
			)
			(placement
				(enabled no)
				(sheetname "")
			)
			(fill
				(thermal_gap 0.5)
				(thermal_bridge_width 0.5)
				(island_removal_mode 0)
			)
			(polygon
				(pts
					(xy 14.195806 2.438654) (xy 14.195806 2.946654) (xy 14.576806 2.946654) (xy 14.576806 2.438654)
				)
			)
		)
		(zone
			(layer "F.Cu")
			(hatch none 0.5)
			(connect_pads
				(clearance 0)
			)
			(min_thickness 0.25)
			(keepout
				(tracks allowed)
				(vias not_allowed)
				(pads allowed)
				(copperpour not_allowed)
				(footprints allowed)
			)
			(placement
				(enabled no)
				(sheetname "")
			)
			(fill
				(thermal_gap 0.5)
				(thermal_bridge_width 0.5)
				(island_removal_mode 0)
			)
			(polygon
				(pts
					(xy 14.195806 2.438654) (xy 14.195806 2.946654) (xy 14.576806 2.946654) (xy 14.576806 2.438654)
				)
			)
		)
	)
)
